(kicad_pcb
	(version 20241229)
	(generator "pcbnew")
	(generator_version "9.0")
	(general
		(thickness 1.711)
		(legacy_teardrops no)
	)
	(paper "A4")
	(title_block
		(title "Antmicro Baseboard for Jetson AGX Thor")
		(date "2026-02-18")
		(rev "1.1.0")
		(company "Antmicro Ltd")
		(comment 1 "www.antmicro.com")
		(comment 9 "footprints 552-556 of 1170")
	)
	(layers
		(0 "F.Cu" signal)
		(4 "In1.Cu" signal)
		(6 "In2.Cu" signal)
		(8 "In3.Cu" signal)
		(10 "In4.Cu" jumper)
		(12 "In5.Cu" signal)
		(14 "In6.Cu" signal)
		(16 "In7.Cu" signal)
		(18 "In8.Cu" signal)
		(2 "B.Cu" signal)
		(9 "F.Adhes" user "F.Adhesive")
		(11 "B.Adhes" user "B.Adhesive")
		(13 "F.Paste" user)
		(15 "B.Paste" user)
		(5 "F.SilkS" user "F.Silkscreen")
		(7 "B.SilkS" user "B.Silkscreen")
		(1 "F.Mask" user)
		(3 "B.Mask" user)
		(17 "Dwgs.User" user "User.Drawings")
		(19 "Cmts.User" user "User.Comments")
		(21 "Eco1.User" user "User.Eco1")
		(23 "Eco2.User" user "User.Eco2")
		(25 "Edge.Cuts" user)
		(27 "Margin" user)
		(31 "F.CrtYd" user "F.Courtyard")
		(29 "B.CrtYd" user "B.Courtyard")
		(35 "F.Fab" user)
		(33 "B.Fab" user)
	)
	(footprint "antmicro-footprints:C_0402_1005Metric"
		(layer "F.Cu")
		(at 211.4 118.3 180)
		(descr "Capacitor SMD 0402")
		(tags "capacitor SMD 0402")
		(property "Reference" "C91"
			(at -1.2 1.4 0)
			(layer "F.SilkS")
			(effects
				(font
					(size 0.7 0.7)
					(thickness 0.15)
				)
				(justify right top)
			)
		)
		(property "Value" "C_100n_0402"
			(at -1.022927 2.155213 0)
			(layer "F.Fab")
			(effects
				(font
					(size 0.7 0.7)
					(thickness 0.15)
				)
				(justify right top)
			)
		)
		(property "Datasheet" "https://www.murata.com/products/productdetail?partno=GRM155R61H104KE14%23"
			(at 0 0 0)
			(layer "F.Fab")
			(hide yes)
			(effects
				(font
					(size 1.27 1.27)
					(thickness 0.15)
				)
			)
		)
		(property "Description" "SMD Multilayer Ceramic Capacitor, 0.1 µF, 50 V, 0402 [1005 Metric], ± 10%, X5R, GRM Series"
			(at 0 0 0)
			(layer "F.Fab")
			(hide yes)
			(effects
				(font
					(size 1.27 1.27)
					(thickness 0.15)
				)
			)
		)
		(property "MPN" "GRM155R61H104KE14D"
			(at 0 0 180)
			(unlocked yes)
			(layer "F.Fab")
			(hide yes)
			(effects
				(font
					(size 1 1)
					(thickness 0.15)
				)
			)
		)
		(property "Val" "100n"
			(at 0 0 180)
			(unlocked yes)
			(layer "F.Fab")
			(hide yes)
			(effects
				(font
					(size 1 1)
					(thickness 0.15)
				)
			)
		)
		(property "Voltage" "50V"
			(at 0 0 180)
			(unlocked yes)
			(layer "F.Fab")
			(hide yes)
			(effects
				(font
					(size 1 1)
					(thickness 0.15)
				)
			)
		)
		(property "Dielectric" "X5R"
			(at 0 0 180)
			(unlocked yes)
			(layer "F.Fab")
			(hide yes)
			(effects
				(font
					(size 1 1)
					(thickness 0.15)
				)
			)
		)
		(property "Manufacturer" "Murata"
			(at 0 0 180)
			(unlocked yes)
			(layer "F.Fab")
			(hide yes)
			(effects
				(font
					(size 1 1)
					(thickness 0.15)
				)
			)
		)
		(property "License" "Apache-2.0"
			(at 0 0 180)
			(unlocked yes)
			(layer "F.Fab")
			(hide yes)
			(effects
				(font
					(size 1 1)
					(thickness 0.15)
				)
			)
		)
		(property "Author" "Antmicro"
			(at 0 0 180)
			(unlocked yes)
			(layer "F.Fab")
			(hide yes)
			(effects
				(font
					(size 1 1)
					(thickness 0.15)
				)
			)
		)
		(sheetname "/USB Hub/")
		(sheetfile "usb_hub.kicad_sch")
		(attr smd)
		(fp_poly
			(pts
				(xy -0.925 -0.47) (xy -0.925 0.47) (xy 0.925 0.47) (xy 0.925 -0.47)
			)
			(stroke
				(width 0.05)
				(type default)
			)
			(fill no)
			(layer "F.CrtYd")
		)
		(fp_line
			(start 0.504 0.248)
			(end -0.494 0.248)
			(stroke
				(width 0.15)
				(type solid)
			)
			(layer "F.Fab")
		)
		(fp_line
			(start 0.504 -0.25)
			(end 0.504 0.248)
			(stroke
				(width 0.15)
				(type solid)
			)
			(layer "F.Fab")
		)
		(fp_line
			(start -0.494 0.248)
			(end -0.494 -0.25)
			(stroke
				(width 0.15)
				(type solid)
			)
			(layer "F.Fab")
		)
		(fp_line
			(start -0.494 -0.25)
			(end 0.504 -0.25)
			(stroke
				(width 0.15)
				(type solid)
			)
			(layer "F.Fab")
		)
		(fp_text user "License: Apache-2.0"
			(at -0.939 5.799 0)
			(layer "F.Fab")
			(effects
				(font
					(size 0.7 0.7)
					(thickness 0.15)
				)
				(justify right top)
			)
		)
		(fp_text user "Author: Antmicro"
			(at -0.939 3.399 0)
			(layer "F.Fab")
			(effects
				(font
					(size 0.7 0.7)
					(thickness 0.15)
				)
				(justify right top)
			)
		)
		(fp_text user "${REFERENCE}"
			(at -0.939 4.599 0)
			(layer "F.Fab")
			(effects
				(font
					(size 0.7 0.7)
					(thickness 0.15)
				)
				(justify right top)
			)
		)
		(pad "1" smd roundrect
			(at -0.48 0 180)
			(size 0.59 0.64)
			(layers "F.Cu" "F.Mask" "F.Paste")
			(roundrect_rratio 0.25)
			(net 1 "GND")
			(pintype "passive")
		)
		(pad "2" smd roundrect
			(at 0.48 0 180)
			(size 0.59 0.64)
			(layers "F.Cu" "F.Mask" "F.Paste")
			(roundrect_rratio 0.25)
			(net 2 "+3V3")
			(pintype "passive")
		)
	)
	(footprint "antmicro-footprints:C_0402_1005Metric"
		(layer "F.Cu")
		(at 211 102.355)
		(descr "Capacitor SMD 0402")
		(tags "capacitor SMD 0402")
		(property "Reference" "C200"
			(at -3.79 0.33 0)
			(layer "F.SilkS")
			(effects
				(font
					(size 0.7 0.7)
					(thickness 0.15)
				)
				(justify left bottom)
			)
		)
		(property "Value" "C_100n_0402"
			(at -1.022927 2.155213 0)
			(layer "F.Fab")
			(effects
				(font
					(size 0.7 0.7)
					(thickness 0.15)
				)
				(justify left bottom)
			)
		)
		(property "Datasheet" "https://www.murata.com/products/productdetail?partno=GRM155R61H104KE14%23"
			(at 0 0 0)
			(layer "F.Fab")
			(hide yes)
			(effects
				(font
					(size 1.27 1.27)
					(thickness 0.15)
				)
			)
		)
		(property "Description" "SMD Multilayer Ceramic Capacitor, 0.1 µF, 50 V, 0402 [1005 Metric], ± 10%, X5R, GRM Series"
			(at 0 0 0)
			(layer "F.Fab")
			(hide yes)
			(effects
				(font
					(size 1.27 1.27)
					(thickness 0.15)
				)
			)
		)
		(property "Manufacturer" "Murata"
			(at 0 0 0)
			(unlocked yes)
			(layer "F.Fab")
			(hide yes)
			(effects
				(font
					(size 1 1)
					(thickness 0.15)
				)
			)
		)
		(property "MPN" "GRM155R61H104KE14D"
			(at 0 0 0)
			(unlocked yes)
			(layer "F.Fab")
			(hide yes)
			(effects
				(font
					(size 1 1)
					(thickness 0.15)
				)
			)
		)
		(property "Val" "100n"
			(at 0 0 0)
			(unlocked yes)
			(layer "F.Fab")
			(hide yes)
			(effects
				(font
					(size 1 1)
					(thickness 0.15)
				)
			)
		)
		(property "License" "Apache-2.0"
			(at 0 0 0)
			(unlocked yes)
			(layer "F.Fab")
			(hide yes)
			(effects
				(font
					(size 1 1)
					(thickness 0.15)
				)
			)
		)
		(property "Author" "Antmicro"
			(at 0 0 0)
			(unlocked yes)
			(layer "F.Fab")
			(hide yes)
			(effects
				(font
					(size 1 1)
					(thickness 0.15)
				)
			)
		)
		(property "Voltage" "50V"
			(at 0 0 0)
			(unlocked yes)
			(layer "F.Fab")
			(hide yes)
			(effects
				(font
					(size 1 1)
					(thickness 0.15)
				)
			)
		)
		(property "Dielectric" "X5R"
			(at 0 0 0)
			(unlocked yes)
			(layer "F.Fab")
			(hide yes)
			(effects
				(font
					(size 1 1)
					(thickness 0.15)
				)
			)
		)
		(sheetname "/Recovery USB/")
		(sheetfile "recovery_usb.kicad_sch")
		(attr smd)
		(fp_rect
			(start -0.925 -0.47)
			(end 0.925 0.47)
			(stroke
				(width 0.05)
				(type default)
			)
			(fill no)
			(layer "F.CrtYd")
		)
		(fp_line
			(start -0.494 -0.25)
			(end 0.504 -0.25)
			(stroke
				(width 0.15)
				(type solid)
			)
			(layer "F.Fab")
		)
		(fp_line
			(start -0.494 0.248)
			(end -0.494 -0.25)
			(stroke
				(width 0.15)
				(type solid)
			)
			(layer "F.Fab")
		)
		(fp_line
			(start 0.504 -0.25)
			(end 0.504 0.248)
			(stroke
				(width 0.15)
				(type solid)
			)
			(layer "F.Fab")
		)
		(fp_line
			(start 0.504 0.248)
			(end -0.494 0.248)
			(stroke
				(width 0.15)
				(type solid)
			)
			(layer "F.Fab")
		)
		(fp_text user "License: Apache-2.0"
			(at -0.939 5.799 0)
			(layer "F.Fab")
			(effects
				(font
					(size 0.7 0.7)
					(thickness 0.15)
				)
				(justify left bottom)
			)
		)
		(fp_text user "Author: Antmicro"
			(at -0.939 3.399 0)
			(layer "F.Fab")
			(effects
				(font
					(size 0.7 0.7)
					(thickness 0.15)
				)
				(justify left bottom)
			)
		)
		(fp_text user "${REFERENCE}"
			(at -0.939 4.599 0)
			(layer "F.Fab")
			(effects
				(font
					(size 0.7 0.7)
					(thickness 0.15)
				)
				(justify left bottom)
			)
		)
		(pad "1" smd roundrect
			(at -0.48 0)
			(size 0.59 0.64)
			(layers "F.Cu" "F.Mask" "F.Paste")
			(roundrect_rratio 0.25)
			(net 618 "/Recovery USB/USBSS0.TX+")
			(pintype "passive")
		)
		(pad "2" smd roundrect
			(at 0.48 0)
			(size 0.59 0.64)
			(layers "F.Cu" "F.Mask" "F.Paste")
			(roundrect_rratio 0.25)
			(net 1129 "/Recovery USB/USBSS_TX_N")
			(pintype "passive")
		)
	)
	(footprint "antmicro-footprints:C_0402_1005Metric"
		(layer "F.Cu")
		(at 211 104.3)
		(descr "Capacitor SMD 0402")
		(tags "capacitor SMD 0402")
		(property "Reference" "C201"
			(at -3.77 0.4 0)
			(layer "F.SilkS")
			(effects
				(font
					(size 0.7 0.7)
					(thickness 0.15)
				)
				(justify left bottom)
			)
		)
		(property "Value" "C_100n_0402"
			(at -1.022927 2.155213 0)
			(layer "F.Fab")
			(effects
				(font
					(size 0.7 0.7)
					(thickness 0.15)
				)
				(justify left bottom)
			)
		)
		(property "Datasheet" "https://www.murata.com/products/productdetail?partno=GRM155R61H104KE14%23"
			(at 0 0 0)
			(layer "F.Fab")
			(hide yes)
			(effects
				(font
					(size 1.27 1.27)
					(thickness 0.15)
				)
			)
		)
		(property "Description" "SMD Multilayer Ceramic Capacitor, 0.1 µF, 50 V, 0402 [1005 Metric], ± 10%, X5R, GRM Series"
			(at 0 0 0)
			(layer "F.Fab")
			(hide yes)
			(effects
				(font
					(size 1.27 1.27)
					(thickness 0.15)
				)
			)
		)
		(property "Manufacturer" "Murata"
			(at 0 0 0)
			(unlocked yes)
			(layer "F.Fab")
			(hide yes)
			(effects
				(font
					(size 1 1)
					(thickness 0.15)
				)
			)
		)
		(property "MPN" "GRM155R61H104KE14D"
			(at 0 0 0)
			(unlocked yes)
			(layer "F.Fab")
			(hide yes)
			(effects
				(font
					(size 1 1)
					(thickness 0.15)
				)
			)
		)
		(property "Val" "100n"
			(at 0 0 0)
			(unlocked yes)
			(layer "F.Fab")
			(hide yes)
			(effects
				(font
					(size 1 1)
					(thickness 0.15)
				)
			)
		)
		(property "License" "Apache-2.0"
			(at 0 0 0)
			(unlocked yes)
			(layer "F.Fab")
			(hide yes)
			(effects
				(font
					(size 1 1)
					(thickness 0.15)
				)
			)
		)
		(property "Author" "Antmicro"
			(at 0 0 0)
			(unlocked yes)
			(layer "F.Fab")
			(hide yes)
			(effects
				(font
					(size 1 1)
					(thickness 0.15)
				)
			)
		)
		(property "Voltage" "50V"
			(at 0 0 0)
			(unlocked yes)
			(layer "F.Fab")
			(hide yes)
			(effects
				(font
					(size 1 1)
					(thickness 0.15)
				)
			)
		)
		(property "Dielectric" "X5R"
			(at 0 0 0)
			(unlocked yes)
			(layer "F.Fab")
			(hide yes)
			(effects
				(font
					(size 1 1)
					(thickness 0.15)
				)
			)
		)
		(sheetname "/Recovery USB/")
		(sheetfile "recovery_usb.kicad_sch")
		(attr smd)
		(fp_rect
			(start -0.925 -0.47)
			(end 0.925 0.47)
			(stroke
				(width 0.05)
				(type default)
			)
			(fill no)
			(layer "F.CrtYd")
		)
		(fp_line
			(start -0.494 -0.25)
			(end 0.504 -0.25)
			(stroke
				(width 0.15)
				(type solid)
			)
			(layer "F.Fab")
		)
		(fp_line
			(start -0.494 0.248)
			(end -0.494 -0.25)
			(stroke
				(width 0.15)
				(type solid)
			)
			(layer "F.Fab")
		)
		(fp_line
			(start 0.504 -0.25)
			(end 0.504 0.248)
			(stroke
				(width 0.15)
				(type solid)
			)
			(layer "F.Fab")
		)
		(fp_line
			(start 0.504 0.248)
			(end -0.494 0.248)
			(stroke
				(width 0.15)
				(type solid)
			)
			(layer "F.Fab")
		)
		(fp_text user "License: Apache-2.0"
			(at -0.939 5.799 0)
			(layer "F.Fab")
			(effects
				(font
					(size 0.7 0.7)
					(thickness 0.15)
				)
				(justify left bottom)
			)
		)
		(fp_text user "${REFERENCE}"
			(at -0.939 4.599 0)
			(layer "F.Fab")
			(effects
				(font
					(size 0.7 0.7)
					(thickness 0.15)
				)
				(justify left bottom)
			)
		)
		(fp_text user "Author: Antmicro"
			(at -0.939 3.399 0)
			(layer "F.Fab")
			(effects
				(font
					(size 0.7 0.7)
					(thickness 0.15)
				)
				(justify left bottom)
			)
		)
		(pad "1" smd roundrect
			(at -0.48 0)
			(size 0.59 0.64)
			(layers "F.Cu" "F.Mask" "F.Paste")
			(roundrect_rratio 0.25)
			(net 622 "/Recovery USB/USBSS0.RX-")
			(pintype "passive")
		)
		(pad "2" smd roundrect
			(at 0.48 0)
			(size 0.59 0.64)
			(layers "F.Cu" "F.Mask" "F.Paste")
			(roundrect_rratio 0.25)
			(net 1130 "/Recovery USB/USBSS_RX_P")
			(pintype "passive")
		)
	)
	(footprint "antmicro-footprints:C_0402_1005Metric"
		(layer "F.Cu")
		(at 198.75 73.5)
		(descr "Capacitor SMD 0402")
		(tags "capacitor SMD 0402")
		(property "Reference" "C147"
			(at -1.65 -0.74 0)
			(layer "F.SilkS")
			(effects
				(font
					(size 0.7 0.7)
					(thickness 0.15)
				)
				(justify left bottom)
			)
		)
		(property "Value" "C_10u_0402"
			(at -1.022927 2.155213 0)
			(layer "F.Fab")
			(effects
				(font
					(size 0.7 0.7)
					(thickness 0.15)
				)
				(justify left bottom)
			)
		)
		(property "Datasheet" "https://www.yageo.com/en/Chart/Download/pdf/CC0402MRX5R5BB106"
			(at 0 0 0)
			(layer "F.Fab")
			(hide yes)
			(effects
				(font
					(size 1.27 1.27)
					(thickness 0.15)
				)
			)
		)
		(property "Description" "SMD Multilayer Ceramic Capacitor, 10 µF, 6.3 V, 0402 [1005 Metric], ± 20%, X5R, CC Series"
			(at 0 0 0)
			(layer "F.Fab")
			(hide yes)
			(effects
				(font
					(size 1.27 1.27)
					(thickness 0.15)
				)
			)
		)
		(property "MPN" "CC0402MRX5R5BB106"
			(at 0 0 0)
			(unlocked yes)
			(layer "F.Fab")
			(hide yes)
			(effects
				(font
					(size 1 1)
					(thickness 0.15)
				)
			)
		)
		(property "Manufacturer" "YAGEO"
			(at 0 0 0)
			(unlocked yes)
			(layer "F.Fab")
			(hide yes)
			(effects
				(font
					(size 1 1)
					(thickness 0.15)
				)
			)
		)
		(property "License" "Apache-2.0"
			(at 0 0 0)
			(unlocked yes)
			(layer "F.Fab")
			(hide yes)
			(effects
				(font
					(size 1 1)
					(thickness 0.15)
				)
			)
		)
		(property "Author" "Antmicro"
			(at 0 0 0)
			(unlocked yes)
			(layer "F.Fab")
			(hide yes)
			(effects
				(font
					(size 1 1)
					(thickness 0.15)
				)
			)
		)
		(property "Val" "10u"
			(at 0 0 0)
			(unlocked yes)
			(layer "F.Fab")
			(hide yes)
			(effects
				(font
					(size 1 1)
					(thickness 0.15)
				)
			)
		)
		(property "Voltage" ""
			(at 0 0 0)
			(unlocked yes)
			(layer "F.Fab")
			(hide yes)
			(effects
				(font
					(size 1 1)
					(thickness 0.15)
				)
			)
		)
		(property "Dielectric" ""
			(at 0 0 0)
			(unlocked yes)
			(layer "F.Fab")
			(hide yes)
			(effects
				(font
					(size 1 1)
					(thickness 0.15)
				)
			)
		)
		(sheetname "/USB Debug, PD/")
		(sheetfile "usb_debug_pd.kicad_sch")
		(attr smd)
		(fp_poly
			(pts
				(xy -0.925 -0.47) (xy -0.925 0.47) (xy 0.925 0.47) (xy 0.925 -0.47)
			)
			(stroke
				(width 0.05)
				(type default)
			)
			(fill no)
			(layer "F.CrtYd")
		)
		(fp_line
			(start -0.494 -0.25)
			(end 0.504 -0.25)
			(stroke
				(width 0.15)
				(type solid)
			)
			(layer "F.Fab")
		)
		(fp_line
			(start -0.494 0.248)
			(end -0.494 -0.25)
			(stroke
				(width 0.15)
				(type solid)
			)
			(layer "F.Fab")
		)
		(fp_line
			(start 0.504 -0.25)
			(end 0.504 0.248)
			(stroke
				(width 0.15)
				(type solid)
			)
			(layer "F.Fab")
		)
		(fp_line
			(start 0.504 0.248)
			(end -0.494 0.248)
			(stroke
				(width 0.15)
				(type solid)
			)
			(layer "F.Fab")
		)
		(fp_text user "Author: Antmicro"
			(at -0.939 3.399 0)
			(layer "F.Fab")
			(effects
				(font
					(size 0.7 0.7)
					(thickness 0.15)
				)
				(justify left bottom)
			)
		)
		(fp_text user "${REFERENCE}"
			(at -0.939 4.599 0)
			(layer "F.Fab")
			(effects
				(font
					(size 0.7 0.7)
					(thickness 0.15)
				)
				(justify left bottom)
			)
		)
		(fp_text user "License: Apache-2.0"
			(at -0.939 5.799 0)
			(layer "F.Fab")
			(effects
				(font
					(size 0.7 0.7)
					(thickness 0.15)
				)
				(justify left bottom)
			)
		)
		(pad "1" smd roundrect
			(at -0.48 0)
			(size 0.59 0.64)
			(layers "F.Cu" "F.Mask" "F.Paste")
			(roundrect_rratio 0.25)
			(net 1 "GND")
			(pintype "passive")
		)
		(pad "2" smd roundrect
			(at 0.48 0)
			(size 0.59 0.64)
			(layers "F.Cu" "F.Mask" "F.Paste")
			(roundrect_rratio 0.25)
			(net 5 "+5V")
			(pintype "passive")
		)
	)
	(footprint "antmicro-footprints:R_0402_1005Metric"
		(layer "F.Cu")
		(at 140.7 111.72 -90)
		(descr "Resistor SMD 0402")
		(tags "resistor SMD 0402")
		(property "Reference" "R405"
			(at 0.78 0.4 90)
			(layer "F.SilkS")
			(effects
				(font
					(size 0.7 0.7)
					(thickness 0.15)
				)
				(justify right top)
			)
		)
		(property "Value" "R_0R_0402"
			(at -1.011843 1.772047 90)
			(layer "F.Fab")
			(effects
				(font
					(size 0.7 0.7)
					(thickness 0.15)
				)
				(justify right top)
			)
		)
		(property "Datasheet" "https://industrial.panasonic.com/cdbs/www-data/pdf/RDA0000/AOA0000C301.pdf"
			(at 0 0 90)
			(layer "F.Fab")
			(hide yes)
			(effects
				(font
					(size 1.27 1.27)
					(thickness 0.15)
				)
			)
		)
		(property "Description" "SMD Chip Resistor, Jumper, 0 ohm, 100 mW, 0402 [1005 Metric], Thick Film, General Purpose"
			(at 0 0 90)
			(layer "F.Fab")
			(hide yes)
			(effects
				(font
					(size 1.27 1.27)
					(thickness 0.15)
				)
			)
		)
		(property "MPN" "ERJ2GE0R00X"
			(at 0 0 270)
			(unlocked yes)
			(layer "F.Fab")
			(hide yes)
			(effects
				(font
					(size 1 1)
					(thickness 0.15)
				)
			)
		)
		(property "Manufacturer" "Panasonic"
			(at 0 0 270)
			(unlocked yes)
			(layer "F.Fab")
			(hide yes)
			(effects
				(font
					(size 1 1)
					(thickness 0.15)
				)
			)
		)
		(property "License" "Apache-2.0"
			(at 0 0 270)
			(unlocked yes)
			(layer "F.Fab")
			(hide yes)
			(effects
				(font
					(size 1 1)
					(thickness 0.15)
				)
			)
		)
		(property "Author" "Antmicro"
			(at 0 0 270)
			(unlocked yes)
			(layer "F.Fab")
			(hide yes)
			(effects
				(font
					(size 1 1)
					(thickness 0.15)
				)
			)
		)
		(property "Val" "0R"
			(at 0 0 270)
			(unlocked yes)
			(layer "F.Fab")
			(hide yes)
			(effects
				(font
					(size 1 1)
					(thickness 0.15)
				)
			)
		)
		(property "Tolerance" "~"
			(at 0 0 270)
			(unlocked yes)
			(layer "F.Fab")
			(hide yes)
			(effects
				(font
					(size 1 1)
					(thickness 0.15)
				)
			)
		)
		(property "Current" "1A"
			(at 0 0 270)
			(unlocked yes)
			(layer "F.Fab")
			(hide yes)
			(effects
				(font
					(size 1 1)
					(thickness 0.15)
				)
			)
		)
		(sheetname "/Peripherals/")
		(sheetfile "peripherals.kicad_sch")
		(attr smd)
		(fp_rect
			(start -0.925 -0.47)
			(end 0.925 0.47)
			(stroke
				(width 0.05)
				(type default)
			)
			(fill no)
			(layer "F.CrtYd")
		)
		(fp_rect
			(start -0.5 -0.25)
			(end 0.5 0.25)
			(stroke
				(width 0.15)
				(type solid)
			)
			(fill no)
			(layer "F.Fab")
		)
		(fp_text user "License: Apache-2.0"
			(at -0.95 5.169 90)
			(layer "F.Fab")
			(effects
				(font
					(size 0.7 0.7)
					(thickness 0.15)
				)
				(justify right top)
			)
		)
		(fp_text user "Author: Antmicro"
			(at -0.95 4.169 90)
			(layer "F.Fab")
			(effects
				(font
					(size 0.7 0.7)
					(thickness 0.15)
				)
				(justify right top)
			)
		)
		(fp_text user "${REFERENCE}"
			(at -0.95 3.168 90)
			(layer "F.Fab")
			(effects
				(font
					(size 0.7 0.7)
					(thickness 0.15)
				)
				(justify right top)
			)
		)
		(pad "1" smd roundrect
			(at -0.48 0 270)
			(size 0.59 0.64)
			(layers "F.Cu" "F.Mask" "F.Paste")
			(roundrect_rratio 0.25)
			(net 1318 "/Peripherals/GPIOEX_P0_6")
			(pintype "passive")
		)
		(pad "2" smd roundrect
			(at 0.48 0 270)
			(size 0.59 0.64)
			(layers "F.Cu" "F.Mask" "F.Paste")
			(roundrect_rratio 0.25)
			(net 90 "/Peripherals/I2C_CONN_PEN")
			(pintype "passive")
		)
	)
)
